(kicad_pcb
	(version 20260206)
	(generator "pcbnew")
	(generator_version "10.0")
	(general
		(thickness 1.6)
		(legacy_teardrops no)
	)
	(paper "A4")
	(title_block
		(title "panther-plus-userver — 13130-1b_20150205.brd")
		(comment 1 "Honey Badger (Wiwynn) / footprints 1387-1394 of 1509")
	)
	(layers
		(0 "F.Cu" signal "TOP")
		(4 "In1.Cu" signal "L2")
		(6 "In2.Cu" signal "L3")
		(8 "In3.Cu" signal "L4")
		(10 "In4.Cu" signal "L5")
		(12 "In5.Cu" signal "L6")
		(14 "In6.Cu" signal "L7")
		(16 "In7.Cu" signal "L8")
		(18 "In8.Cu" signal "L9")
		(20 "In9.Cu" signal "L10")
		(22 "In10.Cu" signal "L11")
		(2 "B.Cu" signal "BOTTOM")
		(9 "F.Adhes" user "F.Adhesive")
		(11 "B.Adhes" user "B.Adhesive")
		(13 "F.Paste" user "Package Geometry/Pastemask Top")
		(15 "B.Paste" user "Package Geometry/Pastemask Bottom")
		(5 "F.SilkS" user "Ref Des/Silkscreen Top")
		(7 "B.SilkS" user "Ref Des/Silkscreen Bottom")
		(1 "F.Mask" user "Board Geometry/Soldermask Top")
		(3 "B.Mask" user "Board Geometry/Soldermask Bottom")
		(17 "Dwgs.User" user "User.Drawings")
		(19 "Cmts.User" user "User.Comments")
		(21 "Eco1.User" user "User.Eco1")
		(23 "Eco2.User" user "User.Eco2")
		(25 "Edge.Cuts" user "Board Geometry/Outline")
		(27 "Margin" user)
		(31 "F.CrtYd" user "Package Geometry/Place Bound Top")
		(29 "B.CrtYd" user "Package Geometry/Place Bound Bottom")
		(35 "F.Fab" user "Ref Des/Assembly Top")
		(33 "B.Fab" user "Ref Des/Assembly Bottom")
	)
	(footprint ""
		(layer "B.Cu")
		(at 201.295 -41.3258 90)
		(property "Reference" "LED11"
			(at 0 0 90)
			(layer "B.SilkS")
			(hide yes)
			(effects
				(font
					(size 1.27 1.27)
				)
				(justify mirror)
			)
		)
		(property "Value" "LED-YG-51-GP"
			(at 0.0381 -2.6162 90)
			(unlocked yes)
			(layer "B.Fab")
			(hide yes)
			(effects
				(font
					(size 1.016 1.016)
					(thickness 0.1524)
				)
				(justify mirror)
			)
		)
		(property "Device Type" "LED1608AKH40"
			(at 0.0381 -4.1402 90)
			(unlocked yes)
			(layer "B.Fab")
			(hide yes)
			(effects
				(font
					(size 1.016 1.016)
					(thickness 0.1524)
				)
				(justify mirror)
			)
		)
		(duplicate_pad_numbers_are_jumpers no)
		(fp_line
			(start 0.5334 1.3081)
			(end -0.5334 1.3081)
			(stroke
				(width 0.254)
				(type default)
			)
			(layer "B.SilkS")
		)
		(fp_rect
			(start 0.6604 1.1811)
			(end -0.6604 -1.1811)
			(stroke
				(width 0)
				(type default)
			)
			(fill no)
			(layer "B.CrtYd")
		)
		(fp_rect
			(start 0.6604 1.1811)
			(end -0.6604 -1.1811)
			(stroke
				(width 0)
				(type default)
			)
			(fill no)
			(layer "B.Fab")
		)
		(pad "A" smd rect
			(at 0 -0.652526 270)
			(size 1.0668 0.8128)
			(layers "B.Cu" "B.Mask" "B.Paste")
			(net "PORT80_R_BIT6")
		)
		(pad "K" smd rect
			(at 0 0.652526 270)
			(size 1.0668 0.8128)
			(layers "B.Cu" "B.Mask" "B.Paste")
			(net "PORT80_BIT6")
		)
	)
	(footprint ""
		(layer "B.Cu")
		(at 184.2008 -30.0228 180)
		(property "Reference" "PR214"
			(at 0 0 0)
			(layer "B.SilkS")
			(hide yes)
			(effects
				(font
					(size 1.27 1.27)
				)
				(justify mirror)
			)
		)
		(property "Value" "100R2F-L1-GP-U"
			(at -1.7907 -1.1176 180)
			(unlocked yes)
			(layer "B.Fab")
			(hide yes)
			(effects
				(font
					(size 1.016 1.016)
					(thickness 0.1524)
				)
				(justify mirror)
			)
		)
		(property "Device Type" "R402H14"
			(at -1.7907 -2.6416 180)
			(unlocked yes)
			(layer "B.Fab")
			(hide yes)
			(effects
				(font
					(size 1.016 1.016)
					(thickness 0.1524)
				)
				(justify mirror)
			)
		)
		(duplicate_pad_numbers_are_jumpers no)
		(fp_rect
			(start 0.381 0.8382)
			(end -0.381 -0.8382)
			(stroke
				(width 0)
				(type default)
			)
			(fill no)
			(layer "B.CrtYd")
		)
		(fp_rect
			(start 0.381 0.8382)
			(end -0.381 -0.8382)
			(stroke
				(width 0)
				(type default)
			)
			(fill no)
			(layer "B.Fab")
		)
		(pad "1" smd custom
			(at 0 -0.4318)
			(size 0.127 0.127)
			(layers "B.Cu" "B.Mask" "B.Paste")
			(net "VR_PVDDR_A_VSEN")
			(options
				(clearance outline)
				(anchor circle)
			)
			(primitives
				(gr_poly
					(pts
						(arc
							(start -0.2032 0.2794)
							(mid -0.239121 0.264521)
							(end -0.254 0.2286)
						)
						(arc
							(start -0.254 -0.2286)
							(mid -0.239121 -0.264521)
							(end -0.2032 -0.2794)
						)
						(arc
							(start 0.2032 -0.2794)
							(mid 0.239121 -0.264521)
							(end 0.254 -0.2286)
						)
						(arc
							(start 0.254 0.2286)
							(mid 0.239121 0.264521)
							(end 0.2032 0.2794)
						)
					)
					(width 0)
					(fill yes)
				)
			)
		)
		(pad "2" smd custom
			(at 0 0.4318)
			(size 0.127 0.127)
			(layers "B.Cu" "B.Mask" "B.Paste")
			(net "VR_PVDDR_A_FB")
			(options
				(clearance outline)
				(anchor circle)
			)
			(primitives
				(gr_poly
					(pts
						(arc
							(start -0.2032 0.2794)
							(mid -0.239121 0.264521)
							(end -0.254 0.2286)
						)
						(arc
							(start -0.254 -0.2286)
							(mid -0.239121 -0.264521)
							(end -0.2032 -0.2794)
						)
						(arc
							(start 0.2032 -0.2794)
							(mid 0.239121 -0.264521)
							(end 0.254 -0.2286)
						)
						(arc
							(start 0.254 0.2286)
							(mid 0.239121 0.264521)
							(end 0.2032 0.2794)
						)
					)
					(width 0)
					(fill yes)
				)
			)
		)
	)
	(footprint ""
		(layer "B.Cu")
		(at 129.921 -11.812778 90)
		(property "Reference" "C354"
			(at 0 0 90)
			(layer "B.SilkS")
			(hide yes)
			(effects
				(font
					(size 1.27 1.27)
				)
				(justify mirror)
			)
		)
		(property "Value" "SC1U6D3V3KX-2GP"
			(at 0.0254 -2.0193 90)
			(unlocked yes)
			(layer "B.Fab")
			(hide yes)
			(effects
				(font
					(size 1.016 1.016)
					(thickness 0.1524)
				)
				(justify mirror)
			)
		)
		(property "Device Type" "C603H36"
			(at 0.0254 -3.5433 90)
			(unlocked yes)
			(layer "B.Fab")
			(hide yes)
			(effects
				(font
					(size 1.016 1.016)
					(thickness 0.1524)
				)
				(justify mirror)
			)
		)
		(duplicate_pad_numbers_are_jumpers no)
		(fp_rect
			(start 0.635 1.1811)
			(end -0.635 -1.1811)
			(stroke
				(width 0)
				(type default)
			)
			(fill no)
			(layer "B.CrtYd")
		)
		(fp_rect
			(start 0.635 1.1811)
			(end -0.635 -1.1811)
			(stroke
				(width 0)
				(type default)
			)
			(fill no)
			(layer "B.Fab")
		)
		(pad "1" smd custom
			(at 0 -0.6604 270)
			(size 0.19685 0.19685)
			(layers "B.Cu" "B.Mask" "B.Paste")
			(net "DDR3_M_B_VREF_DQ0")
			(options
				(clearance outline)
				(anchor circle)
			)
			(primitives
				(gr_poly
					(pts
						(arc
							(start 0.508 0.2921)
							(mid 0.478242 0.363942)
							(end 0.4064 0.3937)
						)
						(arc
							(start -0.4064 0.3937)
							(mid -0.478242 0.363942)
							(end -0.508 0.2921)
						)
						(arc
							(start -0.508 -0.2921)
							(mid -0.478242 -0.363942)
							(end -0.4064 -0.3937)
						)
						(arc
							(start 0.4064 -0.3937)
							(mid 0.478242 -0.363942)
							(end 0.508 -0.2921)
						)
					)
					(width 0)
					(fill yes)
				)
			)
		)
		(pad "2" smd custom
			(at 0 0.6604 270)
			(size 0.19685 0.19685)
			(layers "B.Cu" "B.Mask" "B.Paste")
			(net "GND")
			(options
				(clearance outline)
				(anchor circle)
			)
			(primitives
				(gr_poly
					(pts
						(arc
							(start 0.508 0.2921)
							(mid 0.478242 0.363942)
							(end 0.4064 0.3937)
						)
						(arc
							(start -0.4064 0.3937)
							(mid -0.478242 0.363942)
							(end -0.508 0.2921)
						)
						(arc
							(start -0.508 -0.2921)
							(mid -0.478242 -0.363942)
							(end -0.4064 -0.3937)
						)
						(arc
							(start 0.4064 -0.3937)
							(mid 0.478242 -0.363942)
							(end 0.508 -0.2921)
						)
					)
					(width 0)
					(fill yes)
				)
			)
		)
	)
	(footprint ""
		(layer "B.Cu")
		(at 100.709984 -27.321002)
		(property "Reference" "R374"
			(at 0 0 0)
			(layer "B.SilkS")
			(hide yes)
			(effects
				(font
					(size 1.27 1.27)
				)
				(justify mirror)
			)
		)
		(property "Value" "100R2F-L1-GP-U"
			(at -0.064008 -3.993896 0)
			(unlocked yes)
			(layer "B.Fab")
			(hide yes)
			(effects
				(font
					(size 1.016 1.016)
					(thickness 0.1524)
				)
				(justify mirror)
			)
		)
		(property "Device Type" "R402H14"
			(at -0.064008 -5.517896 0)
			(unlocked yes)
			(layer "B.Fab")
			(hide yes)
			(effects
				(font
					(size 1.016 1.016)
					(thickness 0.1524)
				)
				(justify mirror)
			)
		)
		(duplicate_pad_numbers_are_jumpers no)
		(fp_rect
			(start 0.381 0.8382)
			(end -0.381 -0.8382)
			(stroke
				(width 0)
				(type default)
			)
			(fill no)
			(layer "B.CrtYd")
		)
		(fp_rect
			(start 0.381 0.8382)
			(end -0.381 -0.8382)
			(stroke
				(width 0)
				(type default)
			)
			(fill no)
			(layer "B.Fab")
		)
		(pad "1" smd custom
			(at 0 -0.4318 180)
			(size 0.127 0.127)
			(layers "B.Cu" "B.Mask" "B.Paste")
			(net "M_B_VREF")
			(options
				(clearance outline)
				(anchor circle)
			)
			(primitives
				(gr_poly
					(pts
						(arc
							(start -0.2032 0.2794)
							(mid -0.239121 0.264521)
							(end -0.254 0.2286)
						)
						(arc
							(start -0.254 -0.2286)
							(mid -0.239121 -0.264521)
							(end -0.2032 -0.2794)
						)
						(arc
							(start 0.2032 -0.2794)
							(mid 0.239121 -0.264521)
							(end 0.254 -0.2286)
						)
						(arc
							(start 0.254 0.2286)
							(mid 0.239121 0.264521)
							(end 0.2032 0.2794)
						)
					)
					(width 0)
					(fill yes)
				)
			)
		)
		(pad "2" smd custom
			(at 0 0.4318 180)
			(size 0.127 0.127)
			(layers "B.Cu" "B.Mask" "B.Paste")
			(net "GND")
			(options
				(clearance outline)
				(anchor circle)
			)
			(primitives
				(gr_poly
					(pts
						(arc
							(start -0.2032 0.2794)
							(mid -0.239121 0.264521)
							(end -0.254 0.2286)
						)
						(arc
							(start -0.254 -0.2286)
							(mid -0.239121 -0.264521)
							(end -0.2032 -0.2794)
						)
						(arc
							(start 0.2032 -0.2794)
							(mid 0.239121 -0.264521)
							(end 0.254 -0.2286)
						)
						(arc
							(start 0.254 0.2286)
							(mid 0.239121 0.264521)
							(end 0.2032 0.2794)
						)
					)
					(width 0)
					(fill yes)
				)
			)
		)
	)
	(footprint ""
		(layer "B.Cu")
		(at 25.4635 -12.7)
		(property "Reference" "C273"
			(at 0 0 0)
			(layer "B.SilkS")
			(hide yes)
			(effects
				(font
					(size 1.27 1.27)
				)
				(justify mirror)
			)
		)
		(property "Value" "SCD1U16V2KX-3GP"
			(at -1.1811 -2.7051 0)
			(unlocked yes)
			(layer "B.Fab")
			(hide yes)
			(effects
				(font
					(size 1.016 1.016)
					(thickness 0.1524)
				)
				(justify mirror)
			)
		)
		(property "Device Type" "C402H22"
			(at -1.1811 -4.2291 0)
			(unlocked yes)
			(layer "B.Fab")
			(hide yes)
			(effects
				(font
					(size 1.016 1.016)
					(thickness 0.1524)
				)
				(justify mirror)
			)
		)
		(duplicate_pad_numbers_are_jumpers no)
		(fp_rect
			(start 0.381 0.7366)
			(end -0.381 -0.7366)
			(stroke
				(width 0)
				(type default)
			)
			(fill no)
			(layer "B.CrtYd")
		)
		(fp_rect
			(start 0.381 0.7366)
			(end -0.381 -0.7366)
			(stroke
				(width 0)
				(type default)
			)
			(fill no)
			(layer "B.Fab")
		)
		(pad "1" smd custom
			(at 0 -0.4572 180)
			(size 0.1143 0.1143)
			(layers "B.Cu" "B.Mask" "B.Paste")
			(net "P2E_CPU_ETH10G_C_TX_DN9")
			(options
				(clearance outline)
				(anchor circle)
			)
			(primitives
				(gr_poly
					(pts
						(arc
							(start -0.254 0.1778)
							(mid -0.239121 0.213721)
							(end -0.2032 0.2286)
						)
						(arc
							(start 0.2032 0.2286)
							(mid 0.239121 0.213721)
							(end 0.254 0.1778)
						)
						(arc
							(start 0.254 -0.1778)
							(mid 0.239121 -0.213721)
							(end 0.2032 -0.2286)
						)
						(arc
							(start -0.2032 -0.2286)
							(mid -0.239121 -0.213721)
							(end -0.254 -0.1778)
						)
					)
					(width 0)
					(fill yes)
				)
			)
		)
		(pad "2" smd custom
			(at 0 0.4572 180)
			(size 0.1143 0.1143)
			(layers "B.Cu" "B.Mask" "B.Paste")
			(net "P2E_CPU_ETH10G_TX_DN9")
			(options
				(clearance outline)
				(anchor circle)
			)
			(primitives
				(gr_poly
					(pts
						(arc
							(start -0.254 0.1778)
							(mid -0.239121 0.213721)
							(end -0.2032 0.2286)
						)
						(arc
							(start 0.2032 0.2286)
							(mid 0.239121 0.213721)
							(end 0.254 0.1778)
						)
						(arc
							(start 0.254 -0.1778)
							(mid 0.239121 -0.213721)
							(end 0.2032 -0.2286)
						)
						(arc
							(start -0.2032 -0.2286)
							(mid -0.239121 -0.213721)
							(end -0.254 -0.1778)
						)
					)
					(width 0)
					(fill yes)
				)
			)
		)
	)
	(footprint ""
		(layer "B.Cu")
		(at 129.921 -12.828778 90)
		(property "Reference" "C294"
			(at 0 0 90)
			(layer "B.SilkS")
			(hide yes)
			(effects
				(font
					(size 1.27 1.27)
				)
				(justify mirror)
			)
		)
		(property "Value" "SCD1U16V2KX-3GP"
			(at -1.1811 -2.7051 90)
			(unlocked yes)
			(layer "B.Fab")
			(hide yes)
			(effects
				(font
					(size 1.016 1.016)
					(thickness 0.1524)
				)
				(justify mirror)
			)
		)
		(property "Device Type" "C402H22"
			(at -1.1811 -4.2291 90)
			(unlocked yes)
			(layer "B.Fab")
			(hide yes)
			(effects
				(font
					(size 1.016 1.016)
					(thickness 0.1524)
				)
				(justify mirror)
			)
		)
		(duplicate_pad_numbers_are_jumpers no)
		(fp_rect
			(start 0.381 0.7366)
			(end -0.381 -0.7366)
			(stroke
				(width 0)
				(type default)
			)
			(fill no)
			(layer "B.CrtYd")
		)
		(fp_rect
			(start 0.381 0.7366)
			(end -0.381 -0.7366)
			(stroke
				(width 0)
				(type default)
			)
			(fill no)
			(layer "B.Fab")
		)
		(pad "1" smd custom
			(at 0 -0.4572 270)
			(size 0.1143 0.1143)
			(layers "B.Cu" "B.Mask" "B.Paste")
			(net "DDR3_M_B_VREF_DQ0")
			(options
				(clearance outline)
				(anchor circle)
			)
			(primitives
				(gr_poly
					(pts
						(arc
							(start -0.254 0.1778)
							(mid -0.239121 0.213721)
							(end -0.2032 0.2286)
						)
						(arc
							(start 0.2032 0.2286)
							(mid 0.239121 0.213721)
							(end 0.254 0.1778)
						)
						(arc
							(start 0.254 -0.1778)
							(mid 0.239121 -0.213721)
							(end 0.2032 -0.2286)
						)
						(arc
							(start -0.2032 -0.2286)
							(mid -0.239121 -0.213721)
							(end -0.254 -0.1778)
						)
					)
					(width 0)
					(fill yes)
				)
			)
		)
		(pad "2" smd custom
			(at 0 0.4572 270)
			(size 0.1143 0.1143)
			(layers "B.Cu" "B.Mask" "B.Paste")
			(net "GND")
			(options
				(clearance outline)
				(anchor circle)
			)
			(primitives
				(gr_poly
					(pts
						(arc
							(start -0.254 0.1778)
							(mid -0.239121 0.213721)
							(end -0.2032 0.2286)
						)
						(arc
							(start 0.2032 0.2286)
							(mid 0.239121 0.213721)
							(end 0.254 0.1778)
						)
						(arc
							(start 0.254 -0.1778)
							(mid 0.239121 -0.213721)
							(end 0.2032 -0.2286)
						)
						(arc
							(start -0.2032 -0.2286)
							(mid -0.239121 -0.213721)
							(end -0.254 -0.1778)
						)
					)
					(width 0)
					(fill yes)
				)
			)
		)
	)
	(footprint ""
		(layer "B.Cu")
		(at 103.254048 -35.620452 90)
		(property "Reference" "C205"
			(at 0 0 90)
			(layer "B.SilkS")
			(hide yes)
			(effects
				(font
					(size 1.27 1.27)
				)
				(justify mirror)
			)
		)
		(property "Value" "SC2D2U10V2KX-GP"
			(at -1.1811 -2.7051 90)
			(unlocked yes)
			(layer "B.Fab")
			(hide yes)
			(effects
				(font
					(size 1.016 1.016)
					(thickness 0.1524)
				)
				(justify mirror)
			)
		)
		(property "Device Type" "C402H22"
			(at -1.1811 -4.2291 90)
			(unlocked yes)
			(layer "B.Fab")
			(hide yes)
			(effects
				(font
					(size 1.016 1.016)
					(thickness 0.1524)
				)
				(justify mirror)
			)
		)
		(duplicate_pad_numbers_are_jumpers no)
		(fp_rect
			(start 0.381 0.7366)
			(end -0.381 -0.7366)
			(stroke
				(width 0)
				(type default)
			)
			(fill no)
			(layer "B.CrtYd")
		)
		(fp_rect
			(start 0.381 0.7366)
			(end -0.381 -0.7366)
			(stroke
				(width 0)
				(type default)
			)
			(fill no)
			(layer "B.Fab")
		)
		(pad "1" smd custom
			(at 0 -0.4572 270)
			(size 0.1143 0.1143)
			(layers "B.Cu" "B.Mask" "B.Paste")
			(net "P1V0")
			(options
				(clearance outline)
				(anchor circle)
			)
			(primitives
				(gr_poly
					(pts
						(arc
							(start -0.254 0.1778)
							(mid -0.239121 0.213721)
							(end -0.2032 0.2286)
						)
						(arc
							(start 0.2032 0.2286)
							(mid 0.239121 0.213721)
							(end 0.254 0.1778)
						)
						(arc
							(start 0.254 -0.1778)
							(mid 0.239121 -0.213721)
							(end 0.2032 -0.2286)
						)
						(arc
							(start -0.2032 -0.2286)
							(mid -0.239121 -0.213721)
							(end -0.254 -0.1778)
						)
					)
					(width 0)
					(fill yes)
				)
			)
		)
		(pad "2" smd custom
			(at 0 0.4572 270)
			(size 0.1143 0.1143)
			(layers "B.Cu" "B.Mask" "B.Paste")
			(net "GND")
			(options
				(clearance outline)
				(anchor circle)
			)
			(primitives
				(gr_poly
					(pts
						(arc
							(start -0.254 0.1778)
							(mid -0.239121 0.213721)
							(end -0.2032 0.2286)
						)
						(arc
							(start 0.2032 0.2286)
							(mid 0.239121 0.213721)
							(end 0.254 0.1778)
						)
						(arc
							(start 0.254 -0.1778)
							(mid 0.239121 -0.213721)
							(end 0.2032 -0.2286)
						)
						(arc
							(start -0.2032 -0.2286)
							(mid -0.239121 -0.213721)
							(end -0.254 -0.1778)
						)
					)
					(width 0)
					(fill yes)
				)
			)
		)
	)
	(footprint ""
		(layer "B.Cu")
		(at 204.089 -31.75 90)
		(property "Reference" "C350"
			(at 0 0 90)
			(layer "B.SilkS")
			(hide yes)
			(effects
				(font
					(size 1.27 1.27)
				)
				(justify mirror)
			)
		)
		(property "Value" "SCD1U16V2KX-3GP"
			(at -1.8923 -1.2065 90)
			(unlocked yes)
			(layer "B.Fab")
			(hide yes)
			(effects
				(font
					(size 1.016 1.016)
					(thickness 0.1524)
				)
				(justify mirror)
			)
		)
		(property "Device Type" "C402H22"
			(at -1.8923 -2.7305 90)
			(unlocked yes)
			(layer "B.Fab")
			(hide yes)
			(effects
				(font
					(size 1.016 1.016)
					(thickness 0.1524)
				)
				(justify mirror)
			)
		)
		(duplicate_pad_numbers_are_jumpers no)
		(fp_rect
			(start 0.381 0.7366)
			(end -0.381 -0.7366)
			(stroke
				(width 0)
				(type default)
			)
			(fill no)
			(layer "B.CrtYd")
		)
		(fp_rect
			(start 0.381 0.7366)
			(end -0.381 -0.7366)
			(stroke
				(width 0)
				(type default)
			)
			(fill no)
			(layer "B.Fab")
		)
		(pad "1" smd custom
			(at 0 -0.4572 270)
			(size 0.1143 0.1143)
			(layers "B.Cu" "B.Mask" "B.Paste")
			(net "PV_VDDR")
			(options
				(clearance outline)
				(anchor circle)
			)
			(primitives
				(gr_poly
					(pts
						(arc
							(start -0.254 0.1778)
							(mid -0.239121 0.213721)
							(end -0.2032 0.2286)
						)
						(arc
							(start 0.2032 0.2286)
							(mid 0.239121 0.213721)
							(end 0.254 0.1778)
						)
						(arc
							(start 0.254 -0.1778)
							(mid 0.239121 -0.213721)
							(end 0.2032 -0.2286)
						)
						(arc
							(start -0.2032 -0.2286)
							(mid -0.239121 -0.213721)
							(end -0.254 -0.1778)
						)
					)
					(width 0)
					(fill yes)
				)
			)
		)
		(pad "2" smd custom
			(at 0 0.4572 270)
			(size 0.1143 0.1143)
			(layers "B.Cu" "B.Mask" "B.Paste")
			(net "GND")
			(options
				(clearance outline)
				(anchor circle)
			)
			(primitives
				(gr_poly
					(pts
						(arc
							(start -0.254 0.1778)
							(mid -0.239121 0.213721)
							(end -0.2032 0.2286)
						)
						(arc
							(start 0.2032 0.2286)
							(mid 0.239121 0.213721)
							(end 0.254 0.1778)
						)
						(arc
							(start 0.254 -0.1778)
							(mid 0.239121 -0.213721)
							(end 0.2032 -0.2286)
						)
						(arc
							(start -0.2032 -0.2286)
							(mid -0.239121 -0.213721)
							(end -0.254 -0.1778)
						)
					)
					(width 0)
					(fill yes)
				)
			)
		)
	)
)
